FILE_TYPE = CONNECTIVITY;
{Allegro Design Entry HDL 17.4-2019 S026 (4007227) 1/17/2022}
"PAGE_NUMBER" = 446;
0"NC";
END.
